(kicad_pcb
	(version 20260206)
	(generator "pcbnew")
	(generator_version "10.0")
	(general
		(thickness 1.6)
		(legacy_teardrops no)
	)
	(paper "A4")
	(title_block
		(title "12092022_DA0F0TMDCD0_F0T_Management_Board_D_brd_V3_OCP.brd")
		(comment 1 "Grand Teton / footprints 318-323 of 1440")
	)
	(layers
		(0 "F.Cu" signal "TOP")
		(4 "In1.Cu" signal "GND")
		(6 "In2.Cu" signal "IN1")
		(8 "In3.Cu" signal "GND1")
		(10 "In4.Cu" signal "IN2")
		(12 "In5.Cu" signal "VCC")
		(14 "In6.Cu" signal "VCC1")
		(16 "In7.Cu" signal "IN3")
		(18 "In8.Cu" signal "GND2")
		(20 "In9.Cu" signal "IN4")
		(22 "In10.Cu" signal "GND3")
		(2 "B.Cu" signal "BOTTOM")
		(9 "F.Adhes" user "F.Adhesive")
		(11 "B.Adhes" user "B.Adhesive")
		(13 "F.Paste" user "Package Geometry/Pastemask Top")
		(15 "B.Paste" user "Package Geometry/Pastemask Bottom")
		(5 "F.SilkS" user "Ref Des/Silkscreen Top")
		(7 "B.SilkS" user "Ref Des/Silkscreen Bottom")
		(1 "F.Mask" user "Board Geometry/Soldermask Top")
		(3 "B.Mask" user "Board Geometry/Soldermask Bottom")
		(17 "Dwgs.User" user "User.Drawings")
		(19 "Cmts.User" user "User.Comments")
		(21 "Eco1.User" user "User.Eco1")
		(23 "Eco2.User" user "User.Eco2")
		(25 "Edge.Cuts" user "Board Geometry/Outline")
		(27 "Margin" user)
		(31 "F.CrtYd" user "Package Geometry/Place Bound Top")
		(29 "B.CrtYd" user "Package Geometry/Place Bound Bottom")
		(35 "F.Fab" user "Ref Des/Assembly Top")
		(33 "B.Fab" user "Ref Des/Assembly Bottom")
	)
	(footprint ""
		(layer "F.Cu")
		(at 16.564864 -57.7342 90)
		(property "Reference" "R903"
			(at 0 0 90)
			(layer "F.SilkS")
			(hide yes)
			(effects
				(font
					(size 1.27 1.27)
				)
			)
		)
		(property "Value" ""
			(at 0 0 90)
			(layer "F.Fab")
			(effects
				(font
					(size 1.27 1.27)
				)
			)
		)
		(duplicate_pad_numbers_are_jumpers no)
		(fp_line
			(start 0.7874 -0.4064)
			(end 0.7874 0.4064)
			(stroke
				(width 0.1524)
				(type default)
			)
			(layer "F.SilkS")
		)
		(fp_line
			(start -0.7874 -0.4064)
			(end 0.7874 -0.4064)
			(stroke
				(width 0.1524)
				(type default)
			)
			(layer "F.SilkS")
		)
		(fp_line
			(start 0.7874 0.4064)
			(end -0.7874 0.4064)
			(stroke
				(width 0.1524)
				(type default)
			)
			(layer "F.SilkS")
		)
		(fp_line
			(start -0.7874 0.4064)
			(end -0.7874 -0.4064)
			(stroke
				(width 0.1524)
				(type default)
			)
			(layer "F.SilkS")
		)
		(fp_line
			(start -0.12065 -0.305054)
			(end -0.12065 -0.2794)
			(stroke
				(width 0.1)
				(type default)
			)
			(layer "F.Fab")
		)
		(fp_line
			(start -0.67945 -0.305054)
			(end -0.12065 -0.305054)
			(stroke
				(width 0.1)
				(type default)
			)
			(layer "F.Fab")
		)
		(fp_line
			(start 0.67945 -0.3048)
			(end 0.67945 0.3048)
			(stroke
				(width 0.1)
				(type default)
			)
			(layer "F.Fab")
		)
		(fp_line
			(start 0.12065 -0.3048)
			(end 0.67945 -0.3048)
			(stroke
				(width 0.1)
				(type default)
			)
			(layer "F.Fab")
		)
		(fp_line
			(start 0.12065 -0.2794)
			(end 0.12065 -0.3048)
			(stroke
				(width 0.1)
				(type default)
			)
			(layer "F.Fab")
		)
		(fp_line
			(start -0.12065 -0.2794)
			(end 0.12065 -0.2794)
			(stroke
				(width 0.1)
				(type default)
			)
			(layer "F.Fab")
		)
		(fp_line
			(start 0.120396 0.2794)
			(end -0.12065 0.2794)
			(stroke
				(width 0.1)
				(type default)
			)
			(layer "F.Fab")
		)
		(fp_line
			(start -0.12065 0.2794)
			(end -0.12065 0.3048)
			(stroke
				(width 0.1)
				(type default)
			)
			(layer "F.Fab")
		)
		(fp_line
			(start 0.67945 0.3048)
			(end 0.120396 0.3048)
			(stroke
				(width 0.1)
				(type default)
			)
			(layer "F.Fab")
		)
		(fp_line
			(start 0.120396 0.3048)
			(end 0.120396 0.2794)
			(stroke
				(width 0.1)
				(type default)
			)
			(layer "F.Fab")
		)
		(fp_line
			(start -0.12065 0.3048)
			(end -0.67945 0.3048)
			(stroke
				(width 0.1)
				(type default)
			)
			(layer "F.Fab")
		)
		(fp_line
			(start -0.67945 0.3048)
			(end -0.67945 -0.305054)
			(stroke
				(width 0.1)
				(type default)
			)
			(layer "F.Fab")
		)
		(pad "1" smd circle
			(at -0.40005 0 90)
			(size 0 0)
			(layers "F.Cu" "F.Mask" "F.Paste")
			(net "UART_6_BMC_TXD")
		)
		(pad "2" smd circle
			(at 0.40005 0 90)
			(size 0 0)
			(layers "F.Cu" "F.Mask" "F.Paste")
			(net "UART_6_BMC_TXD_R")
		)
	)
	(footprint ""
		(layer "F.Cu")
		(at 68.5292 -26.3906 -90)
		(property "Reference" "R510"
			(at 0 0 270)
			(layer "F.SilkS")
			(hide yes)
			(effects
				(font
					(size 1.27 1.27)
				)
			)
		)
		(property "Value" ""
			(at 0 0 270)
			(layer "F.Fab")
			(effects
				(font
					(size 1.27 1.27)
				)
			)
		)
		(duplicate_pad_numbers_are_jumpers no)
		(fp_line
			(start -0.7874 0.4064)
			(end -0.7874 -0.4064)
			(stroke
				(width 0.1524)
				(type default)
			)
			(layer "F.SilkS")
		)
		(fp_line
			(start 0.7874 0.4064)
			(end -0.7874 0.4064)
			(stroke
				(width 0.1524)
				(type default)
			)
			(layer "F.SilkS")
		)
		(fp_line
			(start -0.7874 -0.4064)
			(end 0.7874 -0.4064)
			(stroke
				(width 0.1524)
				(type default)
			)
			(layer "F.SilkS")
		)
		(fp_line
			(start 0.7874 -0.4064)
			(end 0.7874 0.4064)
			(stroke
				(width 0.1524)
				(type default)
			)
			(layer "F.SilkS")
		)
		(fp_line
			(start -0.67945 0.3048)
			(end -0.67945 -0.305054)
			(stroke
				(width 0.1)
				(type default)
			)
			(layer "F.Fab")
		)
		(fp_line
			(start -0.12065 0.3048)
			(end -0.67945 0.3048)
			(stroke
				(width 0.1)
				(type default)
			)
			(layer "F.Fab")
		)
		(fp_line
			(start 0.120396 0.3048)
			(end 0.120396 0.2794)
			(stroke
				(width 0.1)
				(type default)
			)
			(layer "F.Fab")
		)
		(fp_line
			(start 0.67945 0.3048)
			(end 0.120396 0.3048)
			(stroke
				(width 0.1)
				(type default)
			)
			(layer "F.Fab")
		)
		(fp_line
			(start -0.12065 0.2794)
			(end -0.12065 0.3048)
			(stroke
				(width 0.1)
				(type default)
			)
			(layer "F.Fab")
		)
		(fp_line
			(start 0.120396 0.2794)
			(end -0.12065 0.2794)
			(stroke
				(width 0.1)
				(type default)
			)
			(layer "F.Fab")
		)
		(fp_line
			(start -0.12065 -0.2794)
			(end 0.12065 -0.2794)
			(stroke
				(width 0.1)
				(type default)
			)
			(layer "F.Fab")
		)
		(fp_line
			(start 0.12065 -0.2794)
			(end 0.12065 -0.3048)
			(stroke
				(width 0.1)
				(type default)
			)
			(layer "F.Fab")
		)
		(fp_line
			(start 0.12065 -0.3048)
			(end 0.67945 -0.3048)
			(stroke
				(width 0.1)
				(type default)
			)
			(layer "F.Fab")
		)
		(fp_line
			(start 0.67945 -0.3048)
			(end 0.67945 0.3048)
			(stroke
				(width 0.1)
				(type default)
			)
			(layer "F.Fab")
		)
		(fp_line
			(start -0.67945 -0.305054)
			(end -0.12065 -0.305054)
			(stroke
				(width 0.1)
				(type default)
			)
			(layer "F.Fab")
		)
		(fp_line
			(start -0.12065 -0.305054)
			(end -0.12065 -0.2794)
			(stroke
				(width 0.1)
				(type default)
			)
			(layer "F.Fab")
		)
		(pad "1" smd circle
			(at -0.40005 0 270)
			(size 0 0)
			(layers "F.Cu" "F.Mask" "F.Paste")
			(net "JTAG_SCM_TCK")
		)
		(pad "2" smd circle
			(at 0.40005 0 270)
			(size 0 0)
			(layers "F.Cu" "F.Mask" "F.Paste")
			(net "JTAG_SCM_PLD_TCK")
		)
	)
	(footprint ""
		(layer "F.Cu")
		(at 76.691744 -35.502088 90)
		(property "Reference" "R328"
			(at 0 0 90)
			(layer "F.SilkS")
			(hide yes)
			(effects
				(font
					(size 1.27 1.27)
				)
			)
		)
		(property "Value" ""
			(at 0 0 90)
			(layer "F.Fab")
			(effects
				(font
					(size 1.27 1.27)
				)
			)
		)
		(duplicate_pad_numbers_are_jumpers no)
		(fp_line
			(start 0.7874 -0.4064)
			(end 0.7874 0.4064)
			(stroke
				(width 0.1524)
				(type default)
			)
			(layer "F.SilkS")
		)
		(fp_line
			(start -0.7874 -0.4064)
			(end 0.7874 -0.4064)
			(stroke
				(width 0.1524)
				(type default)
			)
			(layer "F.SilkS")
		)
		(fp_line
			(start 0.7874 0.4064)
			(end -0.7874 0.4064)
			(stroke
				(width 0.1524)
				(type default)
			)
			(layer "F.SilkS")
		)
		(fp_line
			(start -0.7874 0.4064)
			(end -0.7874 -0.4064)
			(stroke
				(width 0.1524)
				(type default)
			)
			(layer "F.SilkS")
		)
		(fp_line
			(start -0.12065 -0.305054)
			(end -0.12065 -0.2794)
			(stroke
				(width 0.1)
				(type default)
			)
			(layer "F.Fab")
		)
		(fp_line
			(start -0.67945 -0.305054)
			(end -0.12065 -0.305054)
			(stroke
				(width 0.1)
				(type default)
			)
			(layer "F.Fab")
		)
		(fp_line
			(start 0.67945 -0.3048)
			(end 0.67945 0.3048)
			(stroke
				(width 0.1)
				(type default)
			)
			(layer "F.Fab")
		)
		(fp_line
			(start 0.12065 -0.3048)
			(end 0.67945 -0.3048)
			(stroke
				(width 0.1)
				(type default)
			)
			(layer "F.Fab")
		)
		(fp_line
			(start 0.12065 -0.2794)
			(end 0.12065 -0.3048)
			(stroke
				(width 0.1)
				(type default)
			)
			(layer "F.Fab")
		)
		(fp_line
			(start -0.12065 -0.2794)
			(end 0.12065 -0.2794)
			(stroke
				(width 0.1)
				(type default)
			)
			(layer "F.Fab")
		)
		(fp_line
			(start 0.120396 0.2794)
			(end -0.12065 0.2794)
			(stroke
				(width 0.1)
				(type default)
			)
			(layer "F.Fab")
		)
		(fp_line
			(start -0.12065 0.2794)
			(end -0.12065 0.3048)
			(stroke
				(width 0.1)
				(type default)
			)
			(layer "F.Fab")
		)
		(fp_line
			(start 0.67945 0.3048)
			(end 0.120396 0.3048)
			(stroke
				(width 0.1)
				(type default)
			)
			(layer "F.Fab")
		)
		(fp_line
			(start 0.120396 0.3048)
			(end 0.120396 0.2794)
			(stroke
				(width 0.1)
				(type default)
			)
			(layer "F.Fab")
		)
		(fp_line
			(start -0.12065 0.3048)
			(end -0.67945 0.3048)
			(stroke
				(width 0.1)
				(type default)
			)
			(layer "F.Fab")
		)
		(fp_line
			(start -0.67945 0.3048)
			(end -0.67945 -0.305054)
			(stroke
				(width 0.1)
				(type default)
			)
			(layer "F.Fab")
		)
		(pad "1" smd circle
			(at -0.40005 0 90)
			(size 0 0)
			(layers "F.Cu" "F.Mask" "F.Paste")
			(net "GND")
		)
		(pad "2" smd circle
			(at 0.40005 0 90)
			(size 0 0)
			(layers "F.Cu" "F.Mask" "F.Paste")
			(net "M_BMC_DDR4_MA<2>")
		)
	)
	(footprint ""
		(layer "F.Cu")
		(at 48.593248 -20.435062 90)
		(property "Reference" "C178"
			(at 0 0 90)
			(layer "F.SilkS")
			(hide yes)
			(effects
				(font
					(size 1.27 1.27)
				)
			)
		)
		(property "Value" ""
			(at 0 0 90)
			(layer "F.Fab")
			(effects
				(font
					(size 1.27 1.27)
				)
			)
		)
		(duplicate_pad_numbers_are_jumpers no)
		(fp_line
			(start 0.7874 -0.4064)
			(end 0.7874 0.4064)
			(stroke
				(width 0.1524)
				(type default)
			)
			(layer "F.SilkS")
		)
		(fp_line
			(start -0.7874 -0.4064)
			(end 0.7874 -0.4064)
			(stroke
				(width 0.1524)
				(type default)
			)
			(layer "F.SilkS")
		)
		(fp_line
			(start 0.7874 0.4064)
			(end -0.7874 0.4064)
			(stroke
				(width 0.1524)
				(type default)
			)
			(layer "F.SilkS")
		)
		(fp_line
			(start -0.7874 0.4064)
			(end -0.7874 -0.4064)
			(stroke
				(width 0.1524)
				(type default)
			)
			(layer "F.SilkS")
		)
		(fp_line
			(start -0.12065 -0.305054)
			(end -0.12065 -0.2794)
			(stroke
				(width 0.1)
				(type default)
			)
			(layer "F.Fab")
		)
		(fp_line
			(start -0.67945 -0.305054)
			(end -0.12065 -0.305054)
			(stroke
				(width 0.1)
				(type default)
			)
			(layer "F.Fab")
		)
		(fp_line
			(start 0.67945 -0.3048)
			(end 0.67945 0.3048)
			(stroke
				(width 0.1)
				(type default)
			)
			(layer "F.Fab")
		)
		(fp_line
			(start 0.12065 -0.3048)
			(end 0.67945 -0.3048)
			(stroke
				(width 0.1)
				(type default)
			)
			(layer "F.Fab")
		)
		(fp_line
			(start 0.12065 -0.2794)
			(end 0.12065 -0.3048)
			(stroke
				(width 0.1)
				(type default)
			)
			(layer "F.Fab")
		)
		(fp_line
			(start -0.12065 -0.2794)
			(end 0.12065 -0.2794)
			(stroke
				(width 0.1)
				(type default)
			)
			(layer "F.Fab")
		)
		(fp_line
			(start 0.120396 0.2794)
			(end -0.12065 0.2794)
			(stroke
				(width 0.1)
				(type default)
			)
			(layer "F.Fab")
		)
		(fp_line
			(start -0.12065 0.2794)
			(end -0.12065 0.3048)
			(stroke
				(width 0.1)
				(type default)
			)
			(layer "F.Fab")
		)
		(fp_line
			(start 0.67945 0.3048)
			(end 0.120396 0.3048)
			(stroke
				(width 0.1)
				(type default)
			)
			(layer "F.Fab")
		)
		(fp_line
			(start 0.120396 0.3048)
			(end 0.120396 0.2794)
			(stroke
				(width 0.1)
				(type default)
			)
			(layer "F.Fab")
		)
		(fp_line
			(start -0.12065 0.3048)
			(end -0.67945 0.3048)
			(stroke
				(width 0.1)
				(type default)
			)
			(layer "F.Fab")
		)
		(fp_line
			(start -0.67945 0.3048)
			(end -0.67945 -0.305054)
			(stroke
				(width 0.1)
				(type default)
			)
			(layer "F.Fab")
		)
		(pad "1" smd circle
			(at -0.40005 0 90)
			(size 0 0)
			(layers "F.Cu" "F.Mask" "F.Paste")
			(net "P5V_USB_REAR")
		)
		(pad "2" smd circle
			(at 0.40005 0 90)
			(size 0 0)
			(layers "F.Cu" "F.Mask" "F.Paste")
			(net "GND")
		)
	)
	(footprint ""
		(layer "F.Cu")
		(at 36.047172 -83.816952 -90)
		(property "Reference" "R656"
			(at 0 0 270)
			(layer "F.SilkS")
			(hide yes)
			(effects
				(font
					(size 1.27 1.27)
				)
			)
		)
		(property "Value" ""
			(at 0 0 270)
			(layer "F.Fab")
			(effects
				(font
					(size 1.27 1.27)
				)
			)
		)
		(duplicate_pad_numbers_are_jumpers no)
		(fp_line
			(start -0.7874 0.4064)
			(end -0.7874 -0.4064)
			(stroke
				(width 0.1524)
				(type default)
			)
			(layer "F.SilkS")
		)
		(fp_line
			(start 0.7874 0.4064)
			(end -0.7874 0.4064)
			(stroke
				(width 0.1524)
				(type default)
			)
			(layer "F.SilkS")
		)
		(fp_line
			(start -0.7874 -0.4064)
			(end 0.7874 -0.4064)
			(stroke
				(width 0.1524)
				(type default)
			)
			(layer "F.SilkS")
		)
		(fp_line
			(start 0.7874 -0.4064)
			(end 0.7874 0.4064)
			(stroke
				(width 0.1524)
				(type default)
			)
			(layer "F.SilkS")
		)
		(fp_line
			(start -0.67945 0.3048)
			(end -0.67945 -0.305054)
			(stroke
				(width 0.1)
				(type default)
			)
			(layer "F.Fab")
		)
		(fp_line
			(start -0.12065 0.3048)
			(end -0.67945 0.3048)
			(stroke
				(width 0.1)
				(type default)
			)
			(layer "F.Fab")
		)
		(fp_line
			(start 0.120396 0.3048)
			(end 0.120396 0.2794)
			(stroke
				(width 0.1)
				(type default)
			)
			(layer "F.Fab")
		)
		(fp_line
			(start 0.67945 0.3048)
			(end 0.120396 0.3048)
			(stroke
				(width 0.1)
				(type default)
			)
			(layer "F.Fab")
		)
		(fp_line
			(start -0.12065 0.2794)
			(end -0.12065 0.3048)
			(stroke
				(width 0.1)
				(type default)
			)
			(layer "F.Fab")
		)
		(fp_line
			(start 0.120396 0.2794)
			(end -0.12065 0.2794)
			(stroke
				(width 0.1)
				(type default)
			)
			(layer "F.Fab")
		)
		(fp_line
			(start -0.12065 -0.2794)
			(end 0.12065 -0.2794)
			(stroke
				(width 0.1)
				(type default)
			)
			(layer "F.Fab")
		)
		(fp_line
			(start 0.12065 -0.2794)
			(end 0.12065 -0.3048)
			(stroke
				(width 0.1)
				(type default)
			)
			(layer "F.Fab")
		)
		(fp_line
			(start 0.12065 -0.3048)
			(end 0.67945 -0.3048)
			(stroke
				(width 0.1)
				(type default)
			)
			(layer "F.Fab")
		)
		(fp_line
			(start 0.67945 -0.3048)
			(end 0.67945 0.3048)
			(stroke
				(width 0.1)
				(type default)
			)
			(layer "F.Fab")
		)
		(fp_line
			(start -0.67945 -0.305054)
			(end -0.12065 -0.305054)
			(stroke
				(width 0.1)
				(type default)
			)
			(layer "F.Fab")
		)
		(fp_line
			(start -0.12065 -0.305054)
			(end -0.12065 -0.2794)
			(stroke
				(width 0.1)
				(type default)
			)
			(layer "F.Fab")
		)
		(pad "1" smd circle
			(at -0.40005 0 270)
			(size 0 0)
			(layers "F.Cu" "F.Mask" "F.Paste")
			(net "P3V3_AUX")
		)
		(pad "2" smd circle
			(at 0.40005 0 270)
			(size 0 0)
			(layers "F.Cu" "F.Mask" "F.Paste")
			(net "EMMC_DT1_R")
		)
	)
	(footprint ""
		(layer "F.Cu")
		(at 68.189094 -93.62694 180)
		(property "Reference" "R498"
			(at 0 0 180)
			(layer "F.SilkS")
			(hide yes)
			(effects
				(font
					(size 1.27 1.27)
				)
			)
		)
		(property "Value" ""
			(at 0 0 180)
			(layer "F.Fab")
			(effects
				(font
					(size 1.27 1.27)
				)
			)
		)
		(duplicate_pad_numbers_are_jumpers no)
		(fp_line
			(start 0.7874 0.4064)
			(end -0.7874 0.4064)
			(stroke
				(width 0.1524)
				(type default)
			)
			(layer "F.SilkS")
		)
		(fp_line
			(start 0.7874 -0.4064)
			(end 0.7874 0.4064)
			(stroke
				(width 0.1524)
				(type default)
			)
			(layer "F.SilkS")
		)
		(fp_line
			(start -0.7874 0.4064)
			(end -0.7874 -0.4064)
			(stroke
				(width 0.1524)
				(type default)
			)
			(layer "F.SilkS")
		)
		(fp_line
			(start -0.7874 -0.4064)
			(end 0.7874 -0.4064)
			(stroke
				(width 0.1524)
				(type default)
			)
			(layer "F.SilkS")
		)
		(fp_line
			(start 0.67945 0.3048)
			(end 0.120396 0.3048)
			(stroke
				(width 0.1)
				(type default)
			)
			(layer "F.Fab")
		)
		(fp_line
			(start 0.67945 -0.3048)
			(end 0.67945 0.3048)
			(stroke
				(width 0.1)
				(type default)
			)
			(layer "F.Fab")
		)
		(fp_line
			(start 0.12065 -0.2794)
			(end 0.12065 -0.3048)
			(stroke
				(width 0.1)
				(type default)
			)
			(layer "F.Fab")
		)
		(fp_line
			(start 0.12065 -0.3048)
			(end 0.67945 -0.3048)
			(stroke
				(width 0.1)
				(type default)
			)
			(layer "F.Fab")
		)
		(fp_line
			(start 0.120396 0.3048)
			(end 0.120396 0.2794)
			(stroke
				(width 0.1)
				(type default)
			)
			(layer "F.Fab")
		)
		(fp_line
			(start 0.120396 0.2794)
			(end -0.12065 0.2794)
			(stroke
				(width 0.1)
				(type default)
			)
			(layer "F.Fab")
		)
		(fp_line
			(start -0.12065 0.3048)
			(end -0.67945 0.3048)
			(stroke
				(width 0.1)
				(type default)
			)
			(layer "F.Fab")
		)
		(fp_line
			(start -0.12065 0.2794)
			(end -0.12065 0.3048)
			(stroke
				(width 0.1)
				(type default)
			)
			(layer "F.Fab")
		)
		(fp_line
			(start -0.12065 -0.2794)
			(end 0.12065 -0.2794)
			(stroke
				(width 0.1)
				(type default)
			)
			(layer "F.Fab")
		)
		(fp_line
			(start -0.12065 -0.305054)
			(end -0.12065 -0.2794)
			(stroke
				(width 0.1)
				(type default)
			)
			(layer "F.Fab")
		)
		(fp_line
			(start -0.67945 0.3048)
			(end -0.67945 -0.305054)
			(stroke
				(width 0.1)
				(type default)
			)
			(layer "F.Fab")
		)
		(fp_line
			(start -0.67945 -0.305054)
			(end -0.12065 -0.305054)
			(stroke
				(width 0.1)
				(type default)
			)
			(layer "F.Fab")
		)
		(pad "1" smd circle
			(at -0.40005 0 180)
			(size 0 0)
			(layers "F.Cu" "F.Mask" "F.Paste")
			(net "SPI_SYS_R_MOSI")
		)
		(pad "2" smd circle
			(at 0.40005 0 180)
			(size 0 0)
			(layers "F.Cu" "F.Mask" "F.Paste")
			(net "SPI_SYS_R1_MOSI")
		)
	)
)
